# T6G (Grand Teton) — schematic parts with pin connectivity, parts 8081–8081 of 8303; source: Cadence DE-HDL packaged netlist (pstxprt.dat, pstxnet.dat, pstchip.dat)

U25  GENOA_SP5  SOCKET6096_13568-001 IO  pkg SOCKET6096_93-4X120-45XA  page 10  (pins 3697-4032 of 6096)
  CN31  VSS_CN31  POWER  = GND
  CN32  P2_RXP3  IN  = P5E_CPU0_P2_RX_DP<3>
  CN33  P2_RXN3  IN  = P5E_CPU0_P2_RX_DN<3>
  CN34  VSS_CN34  POWER  = GND
  CN35  VDDCR_CPU1_CN35  POWER  = PVDDCR_CPU1_P0
  CN36  VDDCR_CPU1_CN36  POWER  = PVDDCR_CPU1_P0
  CN40  VDDCR_CPU1_CN40  POWER  = PVDDCR_CPU1_P0
  CN41  VDDCR_CPU1_CN41  POWER  = PVDDCR_CPU1_P0
  CN42  VSS_CN42  POWER  = GND
  CN43  \p0_txn12||sata14_txn\  OUT  = P5E_CPU0_P0_TX_DN<12>
  CN44  \p0_txp12||sata14_txp\  OUT  = P5E_CPU0_P0_TX_DP<12>
  CN45  VSS_CN45  POWER  = GND
  CN46  \p0_txn9||sata11_txn\  OUT  = P5E_CPU0_P0_TX_DN<9>
  CN47  \p0_txp9||sata11_txp\  OUT  = P5E_CPU0_P0_TX_DP<9>
  CN48  VSS_CN48  POWER  = GND
  CN49  \p0_txn3||sata03_txn\  OUT  = P5E_CPU0_P0_TX_DN<3>
  CN50  \p0_txp3||sata03_txp\  OUT  = P5E_CPU0_P0_TX_DP<3>
  CN51  VSS_CN51  POWER  = GND
  CN52  \p0_txn0||sata00_txn\  OUT  = P5E_CPU0_P0_TX_DN<0>
  CN53  \p0_txp0||sata00_txp\  OUT  = P5E_CPU0_P0_TX_DP<0>
  CN54  VSS_CN54  POWER  = GND
  CN55  MCB_DATA13  BI  = M_C_CPU0_SB_DQ<13>
  CN56  VSS_CN56  POWER  = GND
  CN57  MCB_DATA14  BI  = M_C_CPU0_SB_DQ<14>
  CN58  VDDIO_CN58  POWER  = PVDDIO_P0
  CN59  MDB_DATA13  BI  = M_D_CPU0_SB_DQ<13>
  CN60  MDB_DATA14  BI  = M_D_CPU0_SB_DQ<14>
  CN61  VSS_CN61  POWER  = GND
  CN62  MBB_DATA13  BI  = M_B_CPU0_SB_DQ<13>
  CN63  VSS_CN63  POWER  = GND
  CN64  MBB_DATA14  BI  = M_B_CPU0_SB_DQ<14>
  CN65  VDDIO_CN65  POWER  = PVDDIO_P0
  CN66  MFB_DATA13  BI  = M_F_CPU0_SB_DQ<13>
  CN67  MFB_DATA14  BI  = M_F_CPU0_SB_DQ<14>
  CN68  VSS_CN68  POWER  = GND
  CN69  MEB_DATA13  BI  = M_E_CPU0_SB_DQ<13>
  CN70  VSS_CN70  POWER  = GND
  CN71  MEB_DATA14  BI  = M_E_CPU0_SB_DQ<14>
  CN72  VDDIO_CN72  POWER  = PVDDIO_P0
  CN73  MAB_DATA13  BI  = M_A_CPU0_SB_DQ<13>
  CN74  MAB_DATA14  BI  = M_A_CPU0_SB_DQ<14>
  CN75  VSS_CN75  POWER  = GND
  CP2  MGB_DATA16  BI  = M_G_CPU0_SB_DQ<16>
  CP3  VSS_CP3  POWER  = GND
  CP4  MGB_DATA15  BI  = M_G_CPU0_SB_DQ<15>
  CP5  VSS_CP5  POWER  = GND
  CP6  MKB_DATA16  BI  = M_K_CPU0_SB_DQ<16>
  CP7  MKB_DATA15  BI  = M_K_CPU0_SB_DQ<15>
  CP8  VSS_CP8  POWER  = GND
  CP9  MLB_DATA16  BI  = M_L_CPU0_SB_DQ<16>
  CP10  VSS_CP10  POWER  = GND
  CP11  MLB_DATA15  BI  = M_L_CPU0_SB_DQ<15>
  CP12  VSS_CP12  POWER  = GND
  CP13  MHB_DATA16  BI  = M_H_CPU0_SB_DQ<16>
  CP14  MHB_DATA15  BI  = M_H_CPU0_SB_DQ<15>
  CP15  VSS_CP15  POWER  = GND
  CP16  MJB_DATA16  BI  = M_J_CPU0_SB_DQ<16>
  CP17  VSS_CP17  POWER  = GND
  CP18  MJB_DATA15  BI  = M_J_CPU0_SB_DQ<15>
  CP19  VSS_CP19  POWER  = GND
  CP20  MIB_DATA16  BI  = M_I_CPU0_SB_DQ<16>
  CP21  MIB_DATA15  BI  = M_I_CPU0_SB_DQ<15>
  CP22  VSS_CP22  POWER  = GND
  CP23  VDDCR_CPU1_CP23  POWER  = PVDDCR_CPU1_P0
  CP24  VDDCR_CPU1_CP24  POWER  = PVDDCR_CPU1_P0
  CP25  VSS_CP25  POWER  = GND
  CP26  VDDCR_CPU1_CP26  POWER  = PVDDCR_CPU1_P0
  CP27  VDDCR_CPU1_CP27  POWER  = PVDDCR_CPU1_P0
  CP28  VSS_CP28  POWER  = GND
  CP29  VDDCR_CPU1_CP29  POWER  = PVDDCR_CPU1_P0
  CP30  VDDCR_CPU1_CP30  POWER  = PVDDCR_CPU1_P0
  CP31  VSS_CP31  POWER  = GND
  CP32  VDDCR_CPU1_CP32  POWER  = PVDDCR_CPU1_P0
  CP33  VDDCR_CPU1_CP33  POWER  = PVDDCR_CPU1_P0
  CP34  VSS_CP34  POWER  = GND
  CP35  P2_RXP1  IN  = P5E_CPU0_P2_RX_DP<1>
  CP36  P2_RXN1  IN  = P5E_CPU0_P2_RX_DN<1>
  CP37  VSS_CP37  POWER  = GND
  CP39  VSS_CP39  POWER  = GND
  CP40  \p0_txn14||sata16_txn\  OUT  = P5E_CPU0_P0_TX_DN<14>
  CP41  \p0_txp14||sata16_txp\  OUT  = P5E_CPU0_P0_TX_DP<14>
  CP42  VSS_CP42  POWER  = GND
  CP43  VDDCR_CPU1_CP43  POWER  = PVDDCR_CPU1_P0
  CP44  VDDCR_CPU1_CP44  POWER  = PVDDCR_CPU1_P0
  CP45  VSS_CP45  POWER  = GND
  CP46  VDDCR_CPU1_CP46  POWER  = PVDDCR_CPU1_P0
  CP47  VDDCR_CPU1_CP47  POWER  = PVDDCR_CPU1_P0
  CP48  VSS_CP48  POWER  = GND
  CP49  VDDCR_CPU1_CP49  POWER  = PVDDCR_CPU1_P0
  CP50  VDDCR_CPU1_CP50  POWER  = PVDDCR_CPU1_P0
  CP51  VSS_CP51  POWER  = GND
  CP52  VDDCR_CPU1_CP52  POWER  = PVDDCR_CPU1_P0
  CP53  VDDCR_CPU1_CP53  POWER  = PVDDCR_CPU1_P0
  CP54  VSS_CP54  POWER  = GND
  CP55  MCB_DATA15  BI  = M_C_CPU0_SB_DQ<15>
  CP56  MCB_DATA16  BI  = M_C_CPU0_SB_DQ<16>
  CP57  VSS_CP57  POWER  = GND
  CP58  MDB_DATA15  BI  = M_D_CPU0_SB_DQ<15>
  CP59  VSS_CP59  POWER  = GND
  CP60  MDB_DATA16  BI  = M_D_CPU0_SB_DQ<16>
  CP61  VSS_CP61  POWER  = GND
  CP62  MBB_DATA15  BI  = M_B_CPU0_SB_DQ<15>
  CP63  MBB_DATA16  BI  = M_B_CPU0_SB_DQ<16>
  CP64  VSS_CP64  POWER  = GND
  CP65  MFB_DATA15  BI  = M_F_CPU0_SB_DQ<15>
  CP66  VSS_CP66  POWER  = GND
  CP67  MFB_DATA16  BI  = M_F_CPU0_SB_DQ<16>
  CP68  VSS_CP68  POWER  = GND
  CP69  MEB_DATA15  BI  = M_E_CPU0_SB_DQ<15>
  CP70  MEB_DATA16  BI  = M_E_CPU0_SB_DQ<16>
  CP71  VSS_CP71  POWER  = GND
  CP72  MAB_DATA15  BI  = M_A_CPU0_SB_DQ<15>
  CP73  VSS_CP73  POWER  = GND
  CP74  MAB_DATA16  BI  = M_A_CPU0_SB_DQ<16>
  CR1  VSS_CR1  POWER  = GND
  CR2  MGB_DATA18  BI  = M_G_CPU0_SB_DQ<18>
  CR3  MGB_DATA17  BI  = M_G_CPU0_SB_DQ<17>
  CR4  VSS_CR4  POWER  = GND
  CR5  MKB_DATA18  BI  = M_K_CPU0_SB_DQ<18>
  CR6  VSS_CR6  POWER  = GND
  CR7  MKB_DATA17  BI  = M_K_CPU0_SB_DQ<17>
  CR8  VSS_CR8  POWER  = GND
  CR9  MLB_DATA18  BI  = M_L_CPU0_SB_DQ<18>
  CR10  MLB_DATA17  BI  = M_L_CPU0_SB_DQ<17>
  CR11  VSS_CR11  POWER  = GND
  CR12  MHB_DATA18  BI  = M_H_CPU0_SB_DQ<18>
  CR13  VSS_CR13  POWER  = GND
  CR14  MHB_DATA17  BI  = M_H_CPU0_SB_DQ<17>
  CR15  VSS_CR15  POWER  = GND
  CR16  MJB_DATA18  BI  = M_J_CPU0_SB_DQ<18>
  CR17  MJB_DATA17  BI  = M_J_CPU0_SB_DQ<17>
  CR18  VSS_CR18  POWER  = GND
  CR19  MIB_DATA18  BI  = M_I_CPU0_SB_DQ<18>
  CR20  VSS_CR20  POWER  = GND
  CR21  MIB_DATA17  BI  = M_I_CPU0_SB_DQ<17>
  CR22  VSS_CR22  POWER  = GND
  CR23  P2_RXP14  IN  = P5E_CPU0_P2_RX_DP<14>
  CR24  P2_RXN14  IN  = P5E_CPU0_P2_RX_DN<14>
  CR25  VSS_CR25  POWER  = GND
  CR26  P2_RXP11  IN  = P5E_CPU0_P2_RX_DP<11>
  CR27  P2_RXN11  IN  = P5E_CPU0_P2_RX_DN<11>
  CR28  VSS_CR28  POWER  = GND
  CR29  P2_RXP8  IN  = P5E_CPU0_P2_RX_DP<8>
  CR30  P2_RXN8  IN  = P5E_CPU0_P2_RX_DN<8>
  CR31  VSS_CR31  POWER  = GND
  CR32  P2_RXP5  IN  = P5E_CPU0_P2_RX_DP<5>
  CR33  P2_RXN5  IN  = P5E_CPU0_P2_RX_DN<5>
  CR34  VSS_CR34  POWER  = GND
  CR35  VSS_CR35  POWER  = GND
  CR36  VSS_CR36  POWER  = GND
  CR40  VSS_CR40  POWER  = GND
  CR41  VSS_CR41  POWER  = GND
  CR42  VSS_CR42  POWER  = GND
  CR43  \p0_txn10||sata12_txn\  OUT  = P5E_CPU0_P0_TX_DN<10>
  CR44  \p0_txp10||sata12_txp\  OUT  = P5E_CPU0_P0_TX_DP<10>
  CR45  VSS_CR45  POWER  = GND
  CR46  \p0_txn7||sata07_txn\  OUT  = P5E_CPU0_P0_TX_DN<7>
  CR47  \p0_txp7||sata07_txp\  OUT  = P5E_CPU0_P0_TX_DP<7>
  CR48  VSS_CR48  POWER  = GND
  CR49  \p0_txn4||sata04_txn\  OUT  = P5E_CPU0_P0_TX_DN<4>
  CR50  \p0_txp4||sata04_txp\  OUT  = P5E_CPU0_P0_TX_DP<4>
  CR51  VSS_CR51  POWER  = GND
  CR52  \p0_txn1||sata01_txn\  OUT  = P5E_CPU0_P0_TX_DN<1>
  CR53  \p0_txp1||sata01_txp\  OUT  = P5E_CPU0_P0_TX_DP<1>
  CR54  VSS_CR54  POWER  = GND
  CR55  MCB_DATA17  BI  = M_C_CPU0_SB_DQ<17>
  CR56  VSS_CR56  POWER  = GND
  CR57  MCB_DATA18  BI  = M_C_CPU0_SB_DQ<18>
  CR58  VSS_CR58  POWER  = GND
  CR59  MDB_DATA17  BI  = M_D_CPU0_SB_DQ<17>
  CR60  MDB_DATA18  BI  = M_D_CPU0_SB_DQ<18>
  CR61  VSS_CR61  POWER  = GND
  CR62  MBB_DATA17  BI  = M_B_CPU0_SB_DQ<17>
  CR63  VSS_CR63  POWER  = GND
  CR64  MBB_DATA18  BI  = M_B_CPU0_SB_DQ<18>
  CR65  VSS_CR65  POWER  = GND
  CR66  MFB_DATA17  BI  = M_F_CPU0_SB_DQ<17>
  CR67  MFB_DATA18  BI  = M_F_CPU0_SB_DQ<18>
  CR68  VSS_CR68  POWER  = GND
  CR69  MEB_DATA17  BI  = M_E_CPU0_SB_DQ<17>
  CR70  VSS_CR70  POWER  = GND
  CR71  MEB_DATA18  BI  = M_E_CPU0_SB_DQ<18>
  CR72  VSS_CR72  POWER  = GND
  CR73  MAB_DATA17  BI  = M_A_CPU0_SB_DQ<17>
  CR74  MAB_DATA18  BI  = M_A_CPU0_SB_DQ<18>
  CR75  VSS_CR75  POWER  = GND
  CT2  MGB_DQS_H2  BI  = M_G_CPU0_SB_DQS_DP<2>
  CT3  VSS_CT3  POWER  = GND
  CT4  MGB_DATA19  BI  = M_G_CPU0_SB_DQ<19>
  CT5  VDD_11_S3_CT5  POWER  = PVDD11_S3_P0
  CT6  MKB_DQS_H2  BI  = M_K_CPU0_SB_DQS_DP<2>
  CT7  MKB_DATA19  BI  = M_K_CPU0_SB_DQ<19>
  CT8  VSS_CT8  POWER  = GND
  CT9  MLB_DQS_H2  BI  = M_L_CPU0_SB_DQS_DP<2>
  CT10  VSS_CT10  POWER  = GND
  CT11  MLB_DATA19  BI  = M_L_CPU0_SB_DQ<19>
  CT12  VDD_11_S3_CT12  POWER  = PVDD11_S3_P0
  CT13  MHB_DQS_H2  BI  = M_H_CPU0_SB_DQS_DP<2>
  CT14  MHB_DATA19  BI  = M_H_CPU0_SB_DQ<19>
  CT15  VSS_CT15  POWER  = GND
  CT16  MJB_DQS_H2  BI  = M_J_CPU0_SB_DQS_DP<2>
  CT17  VSS_CT17  POWER  = GND
  CT18  MJB_DATA19  BI  = M_J_CPU0_SB_DQ<19>
  CT19  VDD_11_S3_CT19  POWER  = PVDD11_S3_P0
  CT20  MIB_DQS_H2  BI  = M_I_CPU0_SB_DQS_DP<2>
  CT21  MIB_DATA19  BI  = M_I_CPU0_SB_DQ<19>
  CT22  VDD_11_S3_CT22  POWER  = PVDD11_S3_P0
  CT23  VSS_CT23  POWER  = GND
  CT24  VSS_CT24  POWER  = GND
  CT25  VSS_CT25  POWER  = GND
  CT26  VSS_CT26  POWER  = GND
  CT27  VSS_CT27  POWER  = GND
  CT28  VSS_CT28  POWER  = GND
  CT29  VSS_CT29  POWER  = GND
  CT30  VSS_CT30  POWER  = GND
  CT31  VSS_CT31  POWER  = GND
  CT32  VSS_CT32  POWER  = GND
  CT33  VSS_CT33  POWER  = GND
  CT34  VSS_CT34  POWER  = GND
  CT35  P2_RXP2  IN  = P5E_CPU0_P2_RX_DP<2>
  CT36  P2_RXN2  IN  = P5E_CPU0_P2_RX_DN<2>
  CT37  VSS_CT37  POWER  = GND
  CT39  VSS_CT39  POWER  = GND
  CT40  \p0_txn13||sata15_txn\  OUT  = P5E_CPU0_P0_TX_DN<13>
  CT41  \p0_txp13||sata15_txp\  OUT  = P5E_CPU0_P0_TX_DP<13>
  CT42  VSS_CT42  POWER  = GND
  CT43  VSS_CT43  POWER  = GND
  CT44  VSS_CT44  POWER  = GND
  CT45  VSS_CT45  POWER  = GND
  CT46  VSS_CT46  POWER  = GND
  CT47  VSS_CT47  POWER  = GND
  CT48  VSS_CT48  POWER  = GND
  CT49  VSS_CT49  POWER  = GND
  CT50  VSS_CT50  POWER  = GND
  CT51  VSS_CT51  POWER  = GND
  CT52  VSS_CT52  POWER  = GND
  CT53  VSS_CT53  POWER  = GND
  CT54  VDDIO_CT54  POWER  = PVDDIO_P0
  CT55  MCB_DATA19  BI  = M_C_CPU0_SB_DQ<19>
  CT56  MCB_DQS_H2  BI  = M_C_CPU0_SB_DQS_DP<2>
  CT57  VDDIO_CT57  POWER  = PVDDIO_P0
  CT58  MDB_DATA19  BI  = M_D_CPU0_SB_DQ<19>
  CT59  VSS_CT59  POWER  = GND
  CT60  MDB_DQS_H2  BI  = M_D_CPU0_SB_DQS_DP<2>
  CT61  VSS_CT61  POWER  = GND
  CT62  MBB_DATA19  BI  = M_B_CPU0_SB_DQ<19>
  CT63  MBB_DQS_H2  BI  = M_B_CPU0_SB_DQS_DP<2>
  CT64  VDDIO_CT64  POWER  = PVDDIO_P0
  CT65  MFB_DATA19  BI  = M_F_CPU0_SB_DQ<19>
  CT66  VSS_CT66  POWER  = GND
  CT67  MFB_DQS_H2  BI  = M_F_CPU0_SB_DQS_DP<2>
  CT68  VSS_CT68  POWER  = GND
  CT69  MEB_DATA19  BI  = M_E_CPU0_SB_DQ<19>
  CT70  MEB_DQS_H2  BI  = M_E_CPU0_SB_DQS_DP<2>
  CT71  VDDIO_CT71  POWER  = PVDDIO_P0
  CT72  MAB_DATA19  BI  = M_A_CPU0_SB_DQ<19>
  CT73  VSS_CT73  POWER  = GND
  CT74  MAB_DQS_H2  BI  = M_A_CPU0_SB_DQS_DP<2>
  CU1  VSS_CU1  POWER  = GND
  CU2  MGB_DQS_L2  BI  = M_G_CPU0_SB_DQS_DN<2>
  CU3  MGB_DQS_L7  BI  = M_G_CPU0_SB_DQS_DN<7>
  CU4  VSS_CU4  POWER  = GND
  CU5  MKB_DQS_L2  BI  = M_K_CPU0_SB_DQS_DN<2>
  CU6  VSS_CU6  POWER  = GND
  CU7  MKB_DQS_L7  BI  = M_K_CPU0_SB_DQS_DN<7>
  CU8  VSS_CU8  POWER  = GND
  CU9  MLB_DQS_L2  BI  = M_L_CPU0_SB_DQS_DN<2>
  CU10  MLB_DQS_L7  BI  = M_L_CPU0_SB_DQS_DN<7>
  CU11  VSS_CU11  POWER  = GND
  CU12  MHB_DQS_L2  BI  = M_H_CPU0_SB_DQS_DN<2>
  CU13  VSS_CU13  POWER  = GND
  CU14  MHB_DQS_L7  BI  = M_H_CPU0_SB_DQS_DN<7>
  CU15  VSS_CU15  POWER  = GND
  CU16  MJB_DQS_L2  BI  = M_J_CPU0_SB_DQS_DN<2>
  CU17  MJB_DQS_L7  BI  = M_J_CPU0_SB_DQS_DN<7>
  CU18  VSS_CU18  POWER  = GND
  CU19  MIB_DQS_L2  BI  = M_I_CPU0_SB_DQS_DN<2>
  CU20  VSS_CU20  POWER  = GND
  CU21  MIB_DQS_L7  BI  = M_I_CPU0_SB_DQS_DN<7>
  CU22  VSS_CU22  POWER  = GND
  CU23  P3_RXP15  IN  = P5E_CPU0_P3_RX_DP<15>
  CU24  P3_RXN15  IN  = P5E_CPU0_P3_RX_DN<15>
  CU25  VSS_CU25  POWER  = GND
  CU26  P2_RXP10  IN  = P5E_CPU0_P2_RX_DP<10>
  CU27  P2_RXN10  IN  = P5E_CPU0_P2_RX_DN<10>
  CU28  VSS_CU28  POWER  = GND
  CU29  P2_RXP7  IN  = P5E_CPU0_P2_RX_DP<7>
  CU30  P2_RXN7  IN  = P5E_CPU0_P2_RX_DN<7>
  CU31  VSS_CU31  POWER  = GND
  CU32  P2_RXP4  IN  = P5E_CPU0_P2_RX_DP<4>
  CU33  P2_RXN4  IN  = P5E_CPU0_P2_RX_DN<4>
  CU34  VSS_CU34  POWER  = GND
  CU35  VDDCR_CPU1_CU35  POWER  = PVDDCR_CPU1_P0
  CU36  VDDCR_CPU1_CU36  POWER  = PVDDCR_CPU1_P0
  CU40  VDDCR_CPU1_CU40  POWER  = PVDDCR_CPU1_P0
  CU41  VDDCR_CPU1_CU41  POWER  = PVDDCR_CPU1_P0
  CU42  VSS_CU42  POWER  = GND
  CU43  \p0_txn11||sata13_txn\  OUT  = P5E_CPU0_P0_TX_DN<11>
  CU44  \p0_txp11||sata13_txp\  OUT  = P5E_CPU0_P0_TX_DP<11>
  CU45  VSS_CU45  POWER  = GND
  CU46  \p0_txn8||sata10_txn\  OUT  = P5E_CPU0_P0_TX_DN<8>
  CU47  \p0_txp8||sata10_txp\  OUT  = P5E_CPU0_P0_TX_DP<8>
  CU48  VSS_CU48  POWER  = GND
  CU49  \p0_txn5||sata05_txn\  OUT  = P5E_CPU0_P0_TX_DN<5>
  CU50  \p0_txp5||sata05_txp\  OUT  = P5E_CPU0_P0_TX_DP<5>
  CU51  VSS_CU51  POWER  = GND
  CU52  P1_TXN0  OUT  = P5E_CPU0_P1_TX_DN<0>
  CU53  P1_TXP0  OUT  = P5E_CPU0_P1_TX_DP<0>
  CU54  VSS_CU54  POWER  = GND
  CU55  MCB_DQS_L7  BI  = M_C_CPU0_SB_DQS_DN<7>
  CU56  VSS_CU56  POWER  = GND
  CU57  MCB_DQS_L2  BI  = M_C_CPU0_SB_DQS_DN<2>
  CU58  VSS_CU58  POWER  = GND
  CU59  MDB_DQS_L7  BI  = M_D_CPU0_SB_DQS_DN<7>
  CU60  MDB_DQS_L2  BI  = M_D_CPU0_SB_DQS_DN<2>
  CU61  VSS_CU61  POWER  = GND
  CU62  MBB_DQS_L7  BI  = M_B_CPU0_SB_DQS_DN<7>
  CU63  VSS_CU63  POWER  = GND
  CU64  MBB_DQS_L2  BI  = M_B_CPU0_SB_DQS_DN<2>
  CU65  VSS_CU65  POWER  = GND
  CU66  MFB_DQS_L7  BI  = M_F_CPU0_SB_DQS_DN<7>
  CU67  MFB_DQS_L2  BI  = M_F_CPU0_SB_DQS_DN<2>
  CU68  VSS_CU68  POWER  = GND
  CU69  MEB_DQS_L7  BI  = M_E_CPU0_SB_DQS_DN<7>
  CU70  VSS_CU70  POWER  = GND
  CU71  MEB_DQS_L2  BI  = M_E_CPU0_SB_DQS_DN<2>
  CU72  VSS_CU72  POWER  = GND
  CU73  MAB_DQS_L7  BI  = M_A_CPU0_SB_DQS_DN<7>
  CU74  MAB_DQS_L2  BI  = M_A_CPU0_SB_DQS_DN<2>
  CU75  VSS_CU75  POWER  = GND
  CV2  MGB_DATA20  BI  = M_G_CPU0_SB_DQ<20>
  CV3  VSS_CV3  POWER  = GND
  CV4  MGB_DQS_H7  BI  = M_G_CPU0_SB_DQS_DP<7>
  CV5  VSS_CV5  POWER  = GND
  CV6  MKB_DATA20  BI  = M_K_CPU0_SB_DQ<20>
  CV7  MKB_DQS_H7  BI  = M_K_CPU0_SB_DQS_DP<7>
